G04 ================== begin FILE IDENTIFICATION RECORD ==================*
G04 Layout Name:  15968-1a.brd*
G04 Film Name:    TMASK*
G04 File Format:  Gerber RS274X*
G04 File Origin:  Cadence Allegro 16.5-S058*
G04 Origin Date:  Fri Oct 14 10:23:29 2016*
G04 *
G04 Layer:  VIA CLASS/SOLDERMASK_TOP*
G04 Layer:  PIN/SOLDERMASK_TOP*
G04 Layer:  PACKAGE GEOMETRY/SOLDERMASK_TOP*
G04 Layer:  DRAWING FORMAT/LAYER_PCB_STORY*
G04 Layer:  DRAWING FORMAT/LAYER_SOLDER_T*
G04 Layer:  BOARD GEOMETRY/SOLDERMASK_TOP*
G04 *
G04 Offset:    (0.00 0.00)*
G04 Mirror:    No*
G04 Mode:      Positive*
G04 Rotation:  0*
G04 FullContactRelief:  No*
G04 UndefLineWidth:     6.00*
G04 ================== end FILE IDENTIFICATION RECORD ====================*
%FSLAX35Y35*MOIN*%
%IR0*IPPOS*OFA0.00000B0.00000*MIA0B0*SFA1.00000B1.00000*%
%AMMACRO56*
4,1,40,.013,.017,
-.013,.017,
-.013695,.016939,
-.014368,.016759,
-.015,.016464,
-.015571,.016064,
-.016064,.015571,
-.016464,.015,
-.016759,.014368,
-.016939,.013695,
-.017,.013,
-.017,-.013,
-.016939,-.013695,
-.016759,-.014368,
-.016464,-.015,
-.016064,-.015571,
-.015571,-.016064,
-.015,-.016464,
-.014368,-.016759,
-.013695,-.016939,
-.013,-.017,
.013,-.017,
.013695,-.016939,
.014368,-.016759,
.015,-.016464,
.015571,-.016064,
.016064,-.015571,
.016464,-.015,
.016759,-.014368,
.016939,-.013695,
.017,-.013,
.017,.013,
.016939,.013695,
.016759,.014368,
.016464,.015,
.016064,.015571,
.015571,.016064,
.015,.016464,
.014368,.016759,
.013695,.016939,
.013,.017,
0.0*
%
%ADD56MACRO56*%
%AMMACRO20*
4,1,40,.017,-.013,
.017,.013,
.016939,.013695,
.016759,.014368,
.016464,.015,
.016064,.015571,
.015571,.016064,
.015,.016464,
.014368,.016759,
.013695,.016939,
.013,.017,
-.013,.017,
-.013695,.016939,
-.014368,.016759,
-.015,.016464,
-.015571,.016064,
-.016064,.015571,
-.016464,.015,
-.016759,.014368,
-.016939,.013695,
-.017,.013,
-.017,-.013,
-.016939,-.013695,
-.016759,-.014368,
-.016464,-.015,
-.016064,-.015571,
-.015571,-.016064,
-.015,-.016464,
-.014368,-.016759,
-.013695,-.016939,
-.013,-.017,
.013,-.017,
.013695,-.016939,
.014368,-.016759,
.015,-.016464,
.015571,-.016064,
.016064,-.015571,
.016464,-.015,
.016759,-.014368,
.016939,-.013695,
.017,-.013,
0.0*
%
%ADD20MACRO20*%
%ADD15R,.022X.11*%
%ADD65R,.022X.102*%
%ADD14R,.141X.061*%
%ADD39R,.061X.141*%
%ADD41C,.02*%
%AMMACRO23*
21,1,.065,.05,0.0,0.0,135.*%
%ADD23MACRO23*%
%ADD63C,.024*%
%ADD54C,.042*%
%ADD47C,.08*%
%ADD13C,.028*%
%ADD53C,.093*%
%ADD10C,.086*%
%AMMACRO44*
4,1,40,.007,.011,
-.007,.011,
-.007695,.010939,
-.008368,.010759,
-.009,.010464,
-.009571,.010064,
-.010064,.009571,
-.010464,.009,
-.010759,.008368,
-.010939,.007695,
-.011,.007,
-.011,-.007,
-.010939,-.007695,
-.010759,-.008368,
-.010464,-.009,
-.010064,-.009571,
-.009571,-.010064,
-.009,-.010464,
-.008368,-.010759,
-.007695,-.010939,
-.007,-.011,
.007,-.011,
.007695,-.010939,
.008368,-.010759,
.009,-.010464,
.009571,-.010064,
.010064,-.009571,
.010464,-.009,
.010759,-.008368,
.010939,-.007695,
.011,-.007,
.011,.007,
.010939,.007695,
.010759,.008368,
.010464,.009,
.010064,.009571,
.009571,.010064,
.009,.010464,
.008368,.010759,
.007695,.010939,
.007,.011,
0.0*
%
%ADD44MACRO44*%
%ADD38R,.065X.065*%
%AMMACRO32*
4,1,40,.011,-.007,
.011,.007,
.010939,.007695,
.010759,.008368,
.010464,.009,
.010064,.009571,
.009571,.010064,
.009,.010464,
.008368,.010759,
.007695,.010939,
.007,.011,
-.007,.011,
-.007695,.010939,
-.008368,.010759,
-.009,.010464,
-.009571,.010064,
-.010064,.009571,
-.010464,.009,
-.010759,.008368,
-.010939,.007695,
-.011,.007,
-.011,-.007,
-.010939,-.007695,
-.010759,-.008368,
-.010464,-.009,
-.010064,-.009571,
-.009571,-.010064,
-.009,-.010464,
-.008368,-.010759,
-.007695,-.010939,
-.007,-.011,
.007,-.011,
.007695,-.010939,
.008368,-.010759,
.009,-.010464,
.009571,-.010064,
.010064,-.009571,
.010464,-.009,
.010759,-.008368,
.010939,-.007695,
.011,-.007,
0.0*
%
%ADD32MACRO32*%
%AMMACRO50*
4,1,40,-.012,.008,
-.012,-.008,
-.011939,-.008695,
-.011759,-.009368,
-.011464,-.01,
-.011064,-.010571,
-.010571,-.011064,
-.01,-.011464,
-.009368,-.011759,
-.008695,-.011939,
-.008,-.012,
.008,-.012,
.008695,-.011939,
.009368,-.011759,
.01,-.011464,
.010571,-.011064,
.011064,-.010571,
.011464,-.01,
.011759,-.009368,
.011939,-.008695,
.012,-.008,
.012,.008,
.011939,.008695,
.011759,.009368,
.011464,.01,
.011064,.010571,
.010571,.011064,
.01,.011464,
.009368,.011759,
.008695,.011939,
.008,.012,
-.008,.012,
-.008695,.011939,
-.009368,.011759,
-.01,.011464,
-.010571,.011064,
-.011064,.010571,
-.011464,.01,
-.011759,.009368,
-.011939,.008695,
-.012,.008,
0.0*
%
%ADD50MACRO50*%
%AMMACRO25*
4,1,40,.008,.012,
-.008,.012,
-.008695,.011939,
-.009368,.011759,
-.01,.011464,
-.010571,.011064,
-.011064,.010571,
-.011464,.01,
-.011759,.009368,
-.011939,.008695,
-.012,.008,
-.012,-.008,
-.011939,-.008695,
-.011759,-.009368,
-.011464,-.01,
-.011064,-.010571,
-.010571,-.011064,
-.01,-.011464,
-.009368,-.011759,
-.008695,-.011939,
-.008,-.012,
.008,-.012,
.008695,-.011939,
.009368,-.011759,
.01,-.011464,
.010571,-.011064,
.011064,-.010571,
.011464,-.01,
.011759,-.009368,
.011939,-.008695,
.012,-.008,
.012,.008,
.011939,.008695,
.011759,.009368,
.011464,.01,
.011064,.010571,
.010571,.011064,
.01,.011464,
.009368,.011759,
.008695,.011939,
.008,.012,
0.0*
%
%ADD25MACRO25*%
%AMMACRO66*
4,1,40,-.013,-.017,
.013,-.017,
.013695,-.016939,
.014368,-.016759,
.015,-.016464,
.015571,-.016064,
.016064,-.015571,
.016464,-.015,
.016759,-.014368,
.016939,-.013695,
.017,-.013,
.017,.013,
.016939,.013695,
.016759,.014368,
.016464,.015,
.016064,.015571,
.015571,.016064,
.015,.016464,
.014368,.016759,
.013695,.016939,
.013,.017,
-.013,.017,
-.013695,.016939,
-.014368,.016759,
-.015,.016464,
-.015571,.016064,
-.016064,.015571,
-.016464,.015,
-.016759,.014368,
-.016939,.013695,
-.017,.013,
-.017,-.013,
-.016939,-.013695,
-.016759,-.014368,
-.016464,-.015,
-.016064,-.015571,
-.015571,-.016064,
-.015,-.016464,
-.014368,-.016759,
-.013695,-.016939,
-.013,-.017,
0.0*
%
%ADD66MACRO66*%
%AMMACRO42*
4,1,40,-.017,.013,
-.017,-.013,
-.016939,-.013695,
-.016759,-.014368,
-.016464,-.015,
-.016064,-.015571,
-.015571,-.016064,
-.015,-.016464,
-.014368,-.016759,
-.013695,-.016939,
-.013,-.017,
.013,-.017,
.013695,-.016939,
.014368,-.016759,
.015,-.016464,
.015571,-.016064,
.016064,-.015571,
.016464,-.015,
.016759,-.014368,
.016939,-.013695,
.017,-.013,
.017,.013,
.016939,.013695,
.016759,.014368,
.016464,.015,
.016064,.015571,
.015571,.016064,
.015,.016464,
.014368,.016759,
.013695,.016939,
.013,.017,
-.013,.017,
-.013695,.016939,
-.014368,.016759,
-.015,.016464,
-.015571,.016064,
-.016064,.015571,
-.016464,.015,
-.016759,.014368,
-.016939,.013695,
-.017,.013,
0.0*
%
%ADD42MACRO42*%
%AMMACRO45*
4,1,40,.007,.011,
-.007,.011,
-.007695,.010939,
-.008368,.010759,
-.009,.010464,
-.009571,.010064,
-.010064,.009571,
-.010464,.009,
-.010759,.008368,
-.010939,.007695,
-.011,.007,
-.011,-.007,
-.010939,-.007695,
-.010759,-.008368,
-.010464,-.009,
-.010064,-.009571,
-.009571,-.010064,
-.009,-.010464,
-.008368,-.010759,
-.007695,-.010939,
-.007,-.011,
.007,-.011,
.007695,-.010939,
.008368,-.010759,
.009,-.010464,
.009571,-.010064,
.010064,-.009571,
.010464,-.009,
.010759,-.008368,
.010939,-.007695,
.011,-.007,
.011,.007,
.010939,.007695,
.010759,.008368,
.010464,.009,
.010064,.009571,
.009571,.010064,
.009,.010464,
.008368,.010759,
.007695,.010939,
.007,.011,
0.0*
%
%ADD45MACRO45*%
%AMMACRO33*
4,1,40,.011,-.007,
.011,.007,
.010939,.007695,
.010759,.008368,
.010464,.009,
.010064,.009571,
.009571,.010064,
.009,.010464,
.008368,.010759,
.007695,.010939,
.007,.011,
-.007,.011,
-.007695,.010939,
-.008368,.010759,
-.009,.010464,
-.009571,.010064,
-.010064,.009571,
-.010464,.009,
-.010759,.008368,
-.010939,.007695,
-.011,.007,
-.011,-.007,
-.010939,-.007695,
-.010759,-.008368,
-.010464,-.009,
-.010064,-.009571,
-.009571,-.010064,
-.009,-.010464,
-.008368,-.010759,
-.007695,-.010939,
-.007,-.011,
.007,-.011,
.007695,-.010939,
.008368,-.010759,
.009,-.010464,
.009571,-.010064,
.010064,-.009571,
.010464,-.009,
.010759,-.008368,
.010939,-.007695,
.011,-.007,
0.0*
%
%ADD33MACRO33*%
%AMMACRO49*
4,1,40,-.012,.008,
-.012,-.008,
-.011939,-.008695,
-.011759,-.009368,
-.011464,-.01,
-.011064,-.010571,
-.010571,-.011064,
-.01,-.011464,
-.009368,-.011759,
-.008695,-.011939,
-.008,-.012,
.008,-.012,
.008695,-.011939,
.009368,-.011759,
.01,-.011464,
.010571,-.011064,
.011064,-.010571,
.011464,-.01,
.011759,-.009368,
.011939,-.008695,
.012,-.008,
.012,.008,
.011939,.008695,
.011759,.009368,
.011464,.01,
.011064,.010571,
.010571,.011064,
.01,.011464,
.009368,.011759,
.008695,.011939,
.008,.012,
-.008,.012,
-.008695,.011939,
-.009368,.011759,
-.01,.011464,
-.010571,.011064,
-.011064,.010571,
-.011464,.01,
-.011759,.009368,
-.011939,.008695,
-.012,.008,
0.0*
%
%ADD49MACRO49*%
%AMMACRO24*
4,1,40,.008,.012,
-.008,.012,
-.008695,.011939,
-.009368,.011759,
-.01,.011464,
-.010571,.011064,
-.011064,.010571,
-.011464,.01,
-.011759,.009368,
-.011939,.008695,
-.012,.008,
-.012,-.008,
-.011939,-.008695,
-.011759,-.009368,
-.011464,-.01,
-.011064,-.010571,
-.010571,-.011064,
-.01,-.011464,
-.009368,-.011759,
-.008695,-.011939,
-.008,-.012,
.008,-.012,
.008695,-.011939,
.009368,-.011759,
.01,-.011464,
.010571,-.011064,
.011064,-.010571,
.011464,-.01,
.011759,-.009368,
.011939,-.008695,
.012,-.008,
.012,.008,
.011939,.008695,
.011759,.009368,
.011464,.01,
.011064,.010571,
.010571,.011064,
.01,.011464,
.009368,.011759,
.008695,.011939,
.008,.012,
0.0*
%
%ADD24MACRO24*%
%AMMACRO64*
4,1,40,-.013,-.017,
.013,-.017,
.013695,-.016939,
.014368,-.016759,
.015,-.016464,
.015571,-.016064,
.016064,-.015571,
.016464,-.015,
.016759,-.014368,
.016939,-.013695,
.017,-.013,
.017,.013,
.016939,.013695,
.016759,.014368,
.016464,.015,
.016064,.015571,
.015571,.016064,
.015,.016464,
.014368,.016759,
.013695,.016939,
.013,.017,
-.013,.017,
-.013695,.016939,
-.014368,.016759,
-.015,.016464,
-.015571,.016064,
-.016064,.015571,
-.016464,.015,
-.016759,.014368,
-.016939,.013695,
-.017,.013,
-.017,-.013,
-.016939,-.013695,
-.016759,-.014368,
-.016464,-.015,
-.016064,-.015571,
-.015571,-.016064,
-.015,-.016464,
-.014368,-.016759,
-.013695,-.016939,
-.013,-.017,
0.0*
%
%ADD64MACRO64*%
%AMMACRO43*
4,1,40,-.017,.013,
-.017,-.013,
-.016939,-.013695,
-.016759,-.014368,
-.016464,-.015,
-.016064,-.015571,
-.015571,-.016064,
-.015,-.016464,
-.014368,-.016759,
-.013695,-.016939,
-.013,-.017,
.013,-.017,
.013695,-.016939,
.014368,-.016759,
.015,-.016464,
.015571,-.016064,
.016064,-.015571,
.016464,-.015,
.016759,-.014368,
.016939,-.013695,
.017,-.013,
.017,.013,
.016939,.013695,
.016759,.014368,
.016464,.015,
.016064,.015571,
.015571,.016064,
.015,.016464,
.014368,.016759,
.013695,.016939,
.013,.017,
-.013,.017,
-.013695,.016939,
-.014368,.016759,
-.015,.016464,
-.015571,.016064,
-.016064,.015571,
-.016464,.015,
-.016759,.014368,
-.016939,.013695,
-.017,.013,
0.0*
%
%ADD43MACRO43*%
%ADD71C,.101*%
%ADD61R,.012X.052*%
%ADD60R,.052X.012*%
%ADD57R,.06X.014*%
%ADD48R,.016X.04*%
%ADD46R,.014X.06*%
%ADD37R,.036X.012*%
%ADD36R,.012X.036*%
%ADD69R,.012X.036*%
%ADD68R,.036X.012*%
%ADD59R,.046X.012*%
%ADD58R,.012X.046*%
%ADD40R,.05X.065*%
%ADD67R,.055X.042*%
%ADD18R,.065X.05*%
%ADD11R,.045X.055*%
%ADD70R,.055X.045*%
%ADD52R,.016X.048*%
%ADD12C,.394*%
%ADD62R,.146X.146*%
%AMMACRO51*
4,1,40,.024,.012,
.024,-.012,
.023878,-.013389,
.023518,-.014736,
.022928,-.016,
.022128,-.017142,
.021142,-.018128,
.02,-.018928,
.018736,-.019518,
.017389,-.019878,
.016,-.02,
-.016,-.02,
-.017389,-.019878,
-.018736,-.019518,
-.02,-.018928,
-.021142,-.018128,
-.022128,-.017142,
-.022928,-.016,
-.023518,-.014736,
-.023878,-.013389,
-.024,-.012,
-.024,.012,
-.023878,.013389,
-.023518,.014736,
-.022928,.016,
-.022128,.017142,
-.021142,.018128,
-.02,.018928,
-.018736,.019518,
-.017389,.019878,
-.016,.02,
.016,.02,
.017389,.019878,
.018736,.019518,
.02,.018928,
.021142,.018128,
.022128,.017142,
.022928,.016,
.023518,.014736,
.023878,.013389,
.024,.012,
0.0*
%
%ADD51MACRO51*%
%AMMACRO34*
4,1,40,-.007,-.011,
.007,-.011,
.007695,-.010939,
.008368,-.010759,
.009,-.010464,
.009571,-.010064,
.010064,-.009571,
.010464,-.009,
.010759,-.008368,
.010939,-.007695,
.011,-.007,
.011,.007,
.010939,.007695,
.010759,.008368,
.010464,.009,
.010064,.009571,
.009571,.010064,
.009,.010464,
.008368,.010759,
.007695,.010939,
.007,.011,
-.007,.011,
-.007695,.010939,
-.008368,.010759,
-.009,.010464,
-.009571,.010064,
-.010064,.009571,
-.010464,.009,
-.010759,.008368,
-.010939,.007695,
-.011,.007,
-.011,-.007,
-.010939,-.007695,
-.010759,-.008368,
-.010464,-.009,
-.010064,-.009571,
-.009571,-.010064,
-.009,-.010464,
-.008368,-.010759,
-.007695,-.010939,
-.007,-.011,
0.0*
%
%ADD34MACRO34*%
%AMMACRO31*
4,1,40,.012,-.008,
.012,.008,
.011939,.008695,
.011759,.009368,
.011464,.01,
.011064,.010571,
.010571,.011064,
.01,.011464,
.009368,.011759,
.008695,.011939,
.008,.012,
-.008,.012,
-.008695,.011939,
-.009368,.011759,
-.01,.011464,
-.010571,.011064,
-.011064,.010571,
-.011464,.01,
-.011759,.009368,
-.011939,.008695,
-.012,.008,
-.012,-.008,
-.011939,-.008695,
-.011759,-.009368,
-.011464,-.01,
-.011064,-.010571,
-.010571,-.011064,
-.01,-.011464,
-.009368,-.011759,
-.008695,-.011939,
-.008,-.012,
.008,-.012,
.008695,-.011939,
.009368,-.011759,
.01,-.011464,
.010571,-.011064,
.011064,-.010571,
.011464,-.01,
.011759,-.009368,
.011939,-.008695,
.012,-.008,
0.0*
%
%ADD31MACRO31*%
%AMMACRO29*
4,1,40,-.008,-.012,
.008,-.012,
.008695,-.011939,
.009368,-.011759,
.01,-.011464,
.010571,-.011064,
.011064,-.010571,
.011464,-.01,
.011759,-.009368,
.011939,-.008695,
.012,-.008,
.012,.008,
.011939,.008695,
.011759,.009368,
.011464,.01,
.011064,.010571,
.010571,.011064,
.01,.011464,
.009368,.011759,
.008695,.011939,
.008,.012,
-.008,.012,
-.008695,.011939,
-.009368,.011759,
-.01,.011464,
-.010571,.011064,
-.011064,.010571,
-.011464,.01,
-.011759,.009368,
-.011939,.008695,
-.012,.008,
-.012,-.008,
-.011939,-.008695,
-.011759,-.009368,
-.011464,-.01,
-.011064,-.010571,
-.010571,-.011064,
-.01,-.011464,
-.009368,-.011759,
-.008695,-.011939,
-.008,-.012,
0.0*
%
%ADD29MACRO29*%
%AMMACRO27*
4,1,44,-.01414,-.00283,
-.00283,-.01414,
-.002296,-.014589,
-.001693,-.014938,
-.001038,-.015177,
-.000351,-.015298,
.000346,-.015299,
.001033,-.015178,
.001688,-.01494,
.002292,-.014592,
.002827,-.014144,
.00283,-.01414,
.01414,-.00283,
.014589,-.002296,
.014938,-.001693,
.015177,-.001038,
.015298,-.000351,
.015299,.000346,
.015178,.001033,
.01494,.001688,
.014592,.002292,
.014144,.002827,
.01414,.00283,
.00283,.01414,
.002296,.014589,
.001693,.014938,
.001038,.015177,
.000351,.015298,
-.000346,.015299,
-.001033,.015178,
-.001688,.01494,
-.002292,.014592,
-.002827,.014144,
-.00283,.01414,
-.01414,.00283,
-.014589,.002296,
-.014938,.001693,
-.015177,.001038,
-.015298,.000351,
-.015299,-.000346,
-.015178,-.001033,
-.01494,-.001688,
-.014592,-.002292,
-.014144,-.002827,
-.01414,-.00283,
0.0*
%
%ADD27MACRO27*%
%AMMACRO21*
4,1,40,-.01273,-.00283,
-.00283,-.01273,
-.002294,-.013176,
-.00169,-.013525,
-.001035,-.013763,
-.000348,-.013884,
.000349,-.013884,
.001036,-.013763,
.001691,-.013525,
.002295,-.013176,
.00283,-.01273,
.01273,-.00283,
.013176,-.002294,
.013525,-.00169,
.013763,-.001035,
.013884,-.000348,
.013884,.000349,
.013763,.001036,
.013525,.001691,
.013176,.002295,
.01273,.00283,
.00283,.01273,
.002294,.013176,
.00169,.013525,
.001035,.013763,
.000348,.013884,
-.000349,.013884,
-.001036,.013763,
-.001691,.013525,
-.002295,.013176,
-.00283,.01273,
-.01273,.00283,
-.013176,.002294,
-.013525,.00169,
-.013763,.001035,
-.013884,.000348,
-.013884,-.000349,
-.013763,-.001036,
-.013525,-.001691,
-.013176,-.002295,
-.01273,-.00283,
0.0*
%
%ADD21MACRO21*%
%AMMACRO16*
4,1,40,-.011,.007,
-.011,-.007,
-.010939,-.007695,
-.010759,-.008368,
-.010464,-.009,
-.010064,-.009571,
-.009571,-.010064,
-.009,-.010464,
-.008368,-.010759,
-.007695,-.010939,
-.007,-.011,
.007,-.011,
.007695,-.010939,
.008368,-.010759,
.009,-.010464,
.009571,-.010064,
.010064,-.009571,
.010464,-.009,
.010759,-.008368,
.010939,-.007695,
.011,-.007,
.011,.007,
.010939,.007695,
.010759,.008368,
.010464,.009,
.010064,.009571,
.009571,.010064,
.009,.010464,
.008368,.010759,
.007695,.010939,
.007,.011,
-.007,.011,
-.007695,.010939,
-.008368,.010759,
-.009,.010464,
-.009571,.010064,
-.010064,.009571,
-.010464,.009,
-.010759,.008368,
-.010939,.007695,
-.011,.007,
0.0*
%
%ADD16MACRO16*%
%AMMACRO55*
4,1,40,.013,.017,
-.013,.017,
-.013695,.016939,
-.014368,.016759,
-.015,.016464,
-.015571,.016064,
-.016064,.015571,
-.016464,.015,
-.016759,.014368,
-.016939,.013695,
-.017,.013,
-.017,-.013,
-.016939,-.013695,
-.016759,-.014368,
-.016464,-.015,
-.016064,-.015571,
-.015571,-.016064,
-.015,-.016464,
-.014368,-.016759,
-.013695,-.016939,
-.013,-.017,
.013,-.017,
.013695,-.016939,
.014368,-.016759,
.015,-.016464,
.015571,-.016064,
.016064,-.015571,
.016464,-.015,
.016759,-.014368,
.016939,-.013695,
.017,-.013,
.017,.013,
.016939,.013695,
.016759,.014368,
.016464,.015,
.016064,.015571,
.015571,.016064,
.015,.016464,
.014368,.016759,
.013695,.016939,
.013,.017,
0.0*
%
%ADD55MACRO55*%
%AMMACRO19*
4,1,40,.017,-.013,
.017,.013,
.016939,.013695,
.016759,.014368,
.016464,.015,
.016064,.015571,
.015571,.016064,
.015,.016464,
.014368,.016759,
.013695,.016939,
.013,.017,
-.013,.017,
-.013695,.016939,
-.014368,.016759,
-.015,.016464,
-.015571,.016064,
-.016064,.015571,
-.016464,.015,
-.016759,.014368,
-.016939,.013695,
-.017,.013,
-.017,-.013,
-.016939,-.013695,
-.016759,-.014368,
-.016464,-.015,
-.016064,-.015571,
-.015571,-.016064,
-.015,-.016464,
-.014368,-.016759,
-.013695,-.016939,
-.013,-.017,
.013,-.017,
.013695,-.016939,
.014368,-.016759,
.015,-.016464,
.015571,-.016064,
.016064,-.015571,
.016464,-.015,
.016759,-.014368,
.016939,-.013695,
.017,-.013,
0.0*
%
%ADD19MACRO19*%
%AMMACRO35*
4,1,40,-.007,-.011,
.007,-.011,
.007695,-.010939,
.008368,-.010759,
.009,-.010464,
.009571,-.010064,
.010064,-.009571,
.010464,-.009,
.010759,-.008368,
.010939,-.007695,
.011,-.007,
.011,.007,
.010939,.007695,
.010759,.008368,
.010464,.009,
.010064,.009571,
.009571,.010064,
.009,.010464,
.008368,.010759,
.007695,.010939,
.007,.011,
-.007,.011,
-.007695,.010939,
-.008368,.010759,
-.009,.010464,
-.009571,.010064,
-.010064,.009571,
-.010464,.009,
-.010759,.008368,
-.010939,.007695,
-.011,.007,
-.011,-.007,
-.010939,-.007695,
-.010759,-.008368,
-.010464,-.009,
-.010064,-.009571,
-.009571,-.010064,
-.009,-.010464,
-.008368,-.010759,
-.007695,-.010939,
-.007,-.011,
0.0*
%
%ADD35MACRO35*%
%AMMACRO30*
4,1,40,.012,-.008,
.012,.008,
.011939,.008695,
.011759,.009368,
.011464,.01,
.011064,.010571,
.010571,.011064,
.01,.011464,
.009368,.011759,
.008695,.011939,
.008,.012,
-.008,.012,
-.008695,.011939,
-.009368,.011759,
-.01,.011464,
-.010571,.011064,
-.011064,.010571,
-.011464,.01,
-.011759,.009368,
-.011939,.008695,
-.012,.008,
-.012,-.008,
-.011939,-.008695,
-.011759,-.009368,
-.011464,-.01,
-.011064,-.010571,
-.010571,-.011064,
-.01,-.011464,
-.009368,-.011759,
-.008695,-.011939,
-.008,-.012,
.008,-.012,
.008695,-.011939,
.009368,-.011759,
.01,-.011464,
.010571,-.011064,
.011064,-.010571,
.011464,-.01,
.011759,-.009368,
.011939,-.008695,
.012,-.008,
0.0*
%
%ADD30MACRO30*%
%AMMACRO28*
4,1,40,-.008,-.012,
.008,-.012,
.008695,-.011939,
.009368,-.011759,
.01,-.011464,
.010571,-.011064,
.011064,-.010571,
.011464,-.01,
.011759,-.009368,
.011939,-.008695,
.012,-.008,
.012,.008,
.011939,.008695,
.011759,.009368,
.011464,.01,
.011064,.010571,
.010571,.011064,
.01,.011464,
.009368,.011759,
.008695,.011939,
.008,.012,
-.008,.012,
-.008695,.011939,
-.009368,.011759,
-.01,.011464,
-.010571,.011064,
-.011064,.010571,
-.011464,.01,
-.011759,.009368,
-.011939,.008695,
-.012,.008,
-.012,-.008,
-.011939,-.008695,
-.011759,-.009368,
-.011464,-.01,
-.011064,-.010571,
-.010571,-.011064,
-.01,-.011464,
-.009368,-.011759,
-.008695,-.011939,
-.008,-.012,
0.0*
%
%ADD28MACRO28*%
%AMMACRO26*
4,1,44,-.01414,-.00283,
-.00283,-.01414,
-.002296,-.014589,
-.001693,-.014938,
-.001038,-.015177,
-.000351,-.015298,
.000346,-.015299,
.001033,-.015178,
.001688,-.01494,
.002292,-.014592,
.002827,-.014144,
.00283,-.01414,
.01414,-.00283,
.014589,-.002296,
.014938,-.001693,
.015177,-.001038,
.015298,-.000351,
.015299,.000346,
.015178,.001033,
.01494,.001688,
.014592,.002292,
.014144,.002827,
.01414,.00283,
.00283,.01414,
.002296,.014589,
.001693,.014938,
.001038,.015177,
.000351,.015298,
-.000346,.015299,
-.001033,.015178,
-.001688,.01494,
-.002292,.014592,
-.002827,.014144,
-.00283,.01414,
-.01414,.00283,
-.014589,.002296,
-.014938,.001693,
-.015177,.001038,
-.015298,.000351,
-.015299,-.000346,
-.015178,-.001033,
-.01494,-.001688,
-.014592,-.002292,
-.014144,-.002827,
-.01414,-.00283,
0.0*
%
%ADD26MACRO26*%
%AMMACRO22*
4,1,40,-.01273,-.00283,
-.00283,-.01273,
-.002294,-.013176,
-.00169,-.013525,
-.001035,-.013763,
-.000348,-.013884,
.000349,-.013884,
.001036,-.013763,
.001691,-.013525,
.002295,-.013176,
.00283,-.01273,
.01273,-.00283,
.013176,-.002294,
.013525,-.00169,
.013763,-.001035,
.013884,-.000348,
.013884,.000349,
.013763,.001036,
.013525,.001691,
.013176,.002295,
.01273,.00283,
.00283,.01273,
.002294,.013176,
.00169,.013525,
.001035,.013763,
.000348,.013884,
-.000349,.013884,
-.001036,.013763,
-.001691,.013525,
-.002295,.013176,
-.00283,.01273,
-.01273,.00283,
-.013176,.002294,
-.013525,.00169,
-.013763,.001035,
-.013884,.000348,
-.013884,-.000349,
-.013763,-.001036,
-.013525,-.001691,
-.013176,-.002295,
-.01273,-.00283,
0.0*
%
%ADD22MACRO22*%
%AMMACRO17*
4,1,40,-.011,.007,
-.011,-.007,
-.010939,-.007695,
-.010759,-.008368,
-.010464,-.009,
-.010064,-.009571,
-.009571,-.010064,
-.009,-.010464,
-.008368,-.010759,
-.007695,-.010939,
-.007,-.011,
.007,-.011,
.007695,-.010939,
.008368,-.010759,
.009,-.010464,
.009571,-.010064,
.010064,-.009571,
.010464,-.009,
.010759,-.008368,
.010939,-.007695,
.011,-.007,
.011,.007,
.010939,.007695,
.010759,.008368,
.010464,.009,
.010064,.009571,
.009571,.010064,
.009,.010464,
.008368,.010759,
.007695,.010939,
.007,.011,
-.007,.011,
-.007695,.010939,
-.008368,.010759,
-.009,.010464,
-.009571,.010064,
-.010064,.009571,
-.010464,.009,
-.010759,.008368,
-.010939,.007695,
-.011,.007,
0.0*
%
%ADD17MACRO17*%
%ADD72C,.006*%
G75*
%LPD*%
G75*
G36*
G01X72653Y-73646D02*
X405733D01*
Y-58409D01*
X72653D01*
Y-73646D01*
G37*
G36*
G01X440369D02*
X540379D01*
Y-59209D01*
X440369D01*
Y-73646D01*
G37*
G54D10*
X21800Y-41500D03*
X14794Y226306D03*
X542107Y17432D03*
X585785Y228866D03*
X610300Y-43600D03*
X612500Y540800D03*
G54D11*
X28000Y75500D03*
X63100Y82000D03*
X70700D03*
X35600Y75500D03*
X103000Y196800D03*
X110600D03*
G54D20*
X85400Y42800D03*
X89978Y121333D03*
X95068Y121388D03*
X99160Y223424D03*
X89548Y223526D03*
X94401Y223411D03*
X84631Y223540D03*
X157100Y78800D03*
X434600Y16000D03*
G54D30*
X91600Y91200D03*
X65600Y139400D03*
X170600Y107900D03*
X108667Y187305D03*
X108673Y190847D03*
X108588Y183478D03*
X404900Y54873D03*
X404961Y51269D03*
X407955Y65607D03*
X366800Y72500D03*
X461441Y60110D03*
X527900Y196300D03*
G54D21*
X47930Y92365D03*
X50813Y95248D03*
X48691Y149395D03*
X51535Y152305D03*
G54D12*
X15748Y128150D03*
X542913D03*
G54D22*
X45526Y94769D03*
X48409Y97652D03*
X46287Y151799D03*
X49131Y154709D03*
G54D31*
X88000Y91200D03*
X62000Y139400D03*
X105067Y187305D03*
X105073Y190847D03*
X104988Y183478D03*
X167000Y107900D03*
X401300Y54873D03*
X401361Y51269D03*
X404355Y65607D03*
X363200Y72500D03*
X457841Y60110D03*
X524300Y196300D03*
G54D40*
X92700Y34400D03*
X103700D03*
X509994Y212056D03*
X520994D03*
G54D13*
X12100Y180900D03*
X28000Y216500D03*
X102800Y61700D03*
X92400Y85300D03*
X89100Y81000D03*
X50900Y166800D03*
X57400Y146000D03*
X54600Y140600D03*
X90972Y139034D03*
X91004Y134234D03*
X89700Y152300D03*
X93700Y149200D03*
X63400Y168300D03*
X62500Y161700D03*
X76613Y167516D03*
X88400Y158500D03*
X89500Y167700D03*
X70800Y152000D03*
X93200Y156000D03*
X87309Y163428D03*
X92100Y143700D03*
X74100Y221900D03*
X84400Y202800D03*
X89944Y202832D03*
X94900Y198600D03*
X60400Y187700D03*
X68200Y203200D03*
X63300Y203000D03*
X122500Y-6600D03*
X151800Y13100D03*
X142000Y-30200D03*
X110300Y36000D03*
X108600Y73000D03*
X117500Y79148D03*
X120000Y48500D03*
X152500Y67800D03*
X117400Y85048D03*
X109900Y53000D03*
X181800Y110500D03*
X116400Y103800D03*
X186688Y183400D03*
X185788Y188700D03*
X199500Y98100D03*
X251700Y171900D03*
X242100Y171200D03*
X250400Y189100D03*
X211888Y189000D03*
X335100Y31400D03*
X334700Y24369D03*
X339900Y35700D03*
X338100Y65400D03*
X334200Y47700D03*
X342900Y73200D03*
X289000Y176600D03*
X289600Y171800D03*
X319700Y178200D03*
X314000Y178400D03*
X292581Y179869D03*
X309500Y190300D03*
X321700Y190100D03*
X368700Y-1531D03*
X369900Y7300D03*
X391100Y4500D03*
X369700Y12700D03*
X369482Y17496D03*
X396000Y5000D03*
X419450Y16771D03*
X409550Y18971D03*
X411450Y-8329D03*
X408800Y55500D03*
X416500Y76200D03*
X409700Y77200D03*
X422556Y94629D03*
X369900Y23369D03*
X387800Y29800D03*
X380700Y74400D03*
X373000Y44900D03*
X372900Y50000D03*
X393768Y48100D03*
X373100Y55600D03*
X393900Y57900D03*
X389800Y73500D03*
X374800Y29516D03*
X375500Y74100D03*
X370351Y31320D03*
X370800Y72800D03*
X434525Y37420D03*
X444697Y41899D03*
X445185Y62776D03*
X448264Y70300D03*
X445063Y57977D03*
X463919Y56185D03*
X443396Y23617D03*
X444800Y37100D03*
X439800D03*
X508300Y229900D03*
X476797Y222299D03*
X524445Y71497D03*
X522293Y169769D03*
X515100Y169500D03*
X534700Y173200D03*
X537600Y169100D03*
X528800Y170000D03*
X509600Y220100D03*
X517100Y194600D03*
X509300Y198400D03*
G54D50*
X160700Y62300D03*
X146600Y86000D03*
Y82400D03*
Y78700D03*
X292600Y196800D03*
X369200Y35400D03*
X412300Y33400D03*
X451120Y33313D03*
X468991Y60100D03*
X450988Y74043D03*
X454000Y44300D03*
X435234Y84295D03*
X452431Y60176D03*
X516682Y198350D03*
G54D32*
X98700Y60700D03*
X95700Y179800D03*
Y164800D03*
X59300Y157700D03*
X106178Y226617D03*
X63400Y210400D03*
X67400D03*
X71500D03*
X83500D03*
X95900D03*
X55900D03*
X108800Y49100D03*
X116671Y111165D03*
X120998Y111171D03*
X181152Y170042D03*
X185182D03*
X234200Y171400D03*
X301100Y174800D03*
X307000Y178100D03*
X411450Y2402D03*
X400200Y4500D03*
X413800Y22700D03*
X395130Y81602D03*
X399360D03*
X443445Y33007D03*
X450400Y40500D03*
X435287Y33008D03*
X436700Y116000D03*
X526110Y165902D03*
X517530Y165802D03*
G54D23*
X39711Y97911D03*
X47489Y105689D03*
X38232Y154310D03*
X46010Y162088D03*
G54D41*
G01X-84798Y-164972D02*
Y-244972D01*
G01D02*
X1172402D01*
G01X-88798Y-148972D02*
G02I-12000J0D01*
G01X-93948D02*
G02I-6850J0D01*
G01X-100798Y-164972D02*
Y-132972D01*
G01X-84798Y-148972D02*
X-116798D01*
G01X-84798Y-164972D02*
X1172402D01*
G01X-84798Y-200472D02*
X1172402D01*
G01X384902Y-164972D02*
Y-244972D01*
G01X522402Y-164972D02*
Y-244972D01*
G01X637402Y-164972D02*
Y-244972D01*
G01X804902Y-164972D02*
Y-244972D01*
G01X974902Y-164972D02*
Y-244972D01*
G01X1172402Y-164972D02*
Y-244972D01*
G01X1200402Y-148972D02*
G02I-12000J0D01*
G01X1195252D02*
G02I-6850J0D01*
G01X1188402Y-164972D02*
Y-132972D01*
G01X1204402Y-148972D02*
X1172402D01*
X104600Y95000D03*
X102400Y92600D03*
X106800Y92700D03*
X104600Y90500D03*
X79000Y142500D03*
X77000Y140300D03*
X81300Y140400D03*
X79200Y138100D03*
X420322Y56072D03*
X423202Y56119D03*
X426128Y50188D03*
Y53348D03*
X426065Y56213D03*
X426113Y59046D03*
X425971Y62050D03*
X432091Y56151D03*
X429056Y56135D03*
X521900Y179500D03*
X524200Y181600D03*
X519700Y181900D03*
X521900Y184000D03*
G54D14*
X25300Y195900D03*
X44500D03*
X134900Y103000D03*
X154100D03*
X141000Y177100D03*
X121800D03*
G54D51*
X142400Y66700D03*
Y58700D03*
X151200Y62700D03*
G54D60*
X415019Y50154D03*
Y52123D03*
Y54091D03*
Y56060D03*
Y58029D03*
Y59997D03*
Y61966D03*
X437419D03*
Y59997D03*
Y58029D03*
Y56060D03*
Y54091D03*
Y52123D03*
Y50154D03*
G54D24*
X90700Y100700D03*
X65300Y146900D03*
X167500Y189600D03*
X192000Y181500D03*
X404330Y4418D03*
X426919Y38224D03*
G54D33*
X98700Y57300D03*
X95700Y176400D03*
Y161400D03*
X59300Y154300D03*
X106178Y223217D03*
X63400Y207000D03*
X67400D03*
X71500D03*
X83500D03*
X95900D03*
X55900D03*
X108800Y45700D03*
X116671Y107765D03*
X120998Y107771D03*
X181152Y166642D03*
X185182D03*
X234200Y168000D03*
X301100Y171400D03*
X307000Y174700D03*
X411450Y-998D03*
X400200Y1100D03*
X413800Y19300D03*
X395130Y78202D03*
X399360D03*
X443445Y29607D03*
X450400Y37100D03*
X435287Y29608D03*
X436700Y112600D03*
X526110Y162502D03*
X517530Y162402D03*
G54D42*
X99700Y107700D03*
X94985Y107675D03*
X163400Y183800D03*
X428000Y97100D03*
G54D15*
X105355Y-63909D03*
X102205D03*
X99055D03*
X95906D03*
X92756D03*
X89607D03*
X86457D03*
X83307D03*
X80158D03*
X77008D03*
X174646D03*
X171496D03*
X168347D03*
X165197D03*
X162048D03*
X158898D03*
X155748D03*
X152599D03*
X149449D03*
X146300D03*
X143150D03*
X140000D03*
X136851D03*
X133701D03*
X130551D03*
X127402D03*
X124252D03*
X121103D03*
X117953D03*
X114803D03*
X111654D03*
X108504D03*
X265985D03*
X262835D03*
X259685D03*
X256536D03*
X253386D03*
X250237D03*
X247087D03*
X243937D03*
X240788D03*
X237638D03*
X234489D03*
X231339D03*
X228189D03*
X225040D03*
X221890D03*
X218740D03*
X215591D03*
X212441D03*
X209292D03*
X206142D03*
X202992D03*
X199843D03*
X196693D03*
X193544D03*
X190394D03*
X347874D03*
X344725D03*
X341575D03*
X338426D03*
X335276D03*
X332126D03*
X328977D03*
X325827D03*
X322677D03*
X319528D03*
X316378D03*
X313229D03*
X310079D03*
X306929D03*
X303780D03*
X300630D03*
X297481D03*
X294331D03*
X291181D03*
X288032D03*
X284882D03*
X281733D03*
X278583D03*
X275433D03*
X272284D03*
X269134D03*
X401418D03*
X398268D03*
X395118D03*
X391969D03*
X388819D03*
X385670D03*
X382520D03*
X379370D03*
X376221D03*
X373071D03*
X369922D03*
X366772D03*
X363622D03*
X360473D03*
X357323D03*
X354174D03*
X351024D03*
G54D16*
X103300Y14400D03*
X107600D03*
X95700Y168900D03*
X71726Y155766D03*
X75804Y155748D03*
X83300Y158500D03*
X67500Y154200D03*
X63400D03*
X105218Y141258D03*
X75500Y207000D03*
X79500D03*
X91700D03*
X87500D03*
X116000Y14500D03*
X111800D03*
X156300Y15200D03*
X157000Y70800D03*
X137000Y52900D03*
X175320Y173098D03*
X171290D03*
X171300Y186200D03*
X234300Y175700D03*
X327800Y35900D03*
X331500Y28200D03*
X332100Y36000D03*
X345700Y76900D03*
X336300Y35900D03*
X307000Y182200D03*
X413800Y11800D03*
X375600Y78300D03*
X422638Y80676D03*
X418444Y80647D03*
X426696Y80704D03*
X414283Y80676D03*
X371500Y78300D03*
X395148Y69558D03*
X399318D03*
X439418Y29635D03*
X530160Y162498D03*
X521600Y162398D03*
X534348Y162458D03*
X516810Y202098D03*
X512680D03*
G54D34*
X102900Y52600D03*
X71200Y163800D03*
X98089Y135908D03*
X98085Y140036D03*
X105650Y164312D03*
Y168512D03*
X101072Y148907D03*
X101043Y153241D03*
X59700Y168300D03*
X121198Y89357D03*
X128000Y51900D03*
Y47700D03*
Y43500D03*
X115800Y74800D03*
X160300Y66400D03*
X121302Y98010D03*
X168154Y198330D03*
X246400Y180600D03*
Y176500D03*
X246600Y193200D03*
X210500Y195800D03*
X246600Y189000D03*
X237600Y198500D03*
X330400Y19700D03*
X336200Y52200D03*
X334100Y64700D03*
X337800Y69600D03*
X286800Y168400D03*
X305511Y198009D03*
X305400Y193700D03*
Y189700D03*
X296800Y187800D03*
X377087Y17368D03*
X387100Y13200D03*
X387200Y3300D03*
X376900Y7400D03*
X377100Y21500D03*
X390300Y69500D03*
X390200Y59600D03*
X380000Y65400D03*
X380213Y55568D03*
X390200Y46600D03*
X380200Y50700D03*
X380100Y38400D03*
X387100Y25800D03*
X453794Y52538D03*
X453806Y48469D03*
X451660Y66541D03*
X458000Y37100D03*
X429865Y30637D03*
X429800Y26500D03*
X544602Y176160D03*
Y172130D03*
G54D52*
X108040Y59450D03*
X110600D03*
X113160D03*
Y65950D03*
X108040D03*
X125460Y65750D03*
X122900D03*
X120340D03*
Y59250D03*
X125460D03*
G54D70*
X524430Y224202D03*
Y231802D03*
X532360Y224202D03*
Y231802D03*
X540290Y224202D03*
Y231802D03*
X548220Y224202D03*
Y231802D03*
G54D61*
X426219Y44860D03*
X424250D03*
X422282D03*
X420313D03*
Y67260D03*
X422282D03*
X424250D03*
X426219D03*
X432125Y44860D03*
X430156D03*
X428188D03*
Y67260D03*
X430156D03*
X432125D03*
G54D43*
X99700Y113300D03*
X94985Y113275D03*
X163400Y189400D03*
X428000Y102700D03*
G54D25*
X90700Y97100D03*
X65300Y143300D03*
X167500Y186000D03*
X192000Y177900D03*
X404330Y818D03*
X426919Y34624D03*
G54D17*
X103300Y17800D03*
X107600D03*
X95700Y172300D03*
X71726Y159166D03*
X75804Y159148D03*
X83300Y161900D03*
X67500Y157600D03*
X63400D03*
X105218Y144658D03*
X75500Y210400D03*
X79500D03*
X91700D03*
X87500D03*
X116000Y17900D03*
X111800D03*
X156300Y18600D03*
X157000Y74200D03*
X137000Y56300D03*
X175320Y176498D03*
X171290D03*
X171300Y189600D03*
X234300Y179100D03*
X327800Y39300D03*
X331500Y31600D03*
X332100Y39400D03*
X345700Y80300D03*
X336300Y39300D03*
X307000Y185600D03*
X413800Y15200D03*
X375600Y81700D03*
X422638Y84076D03*
X418444Y84047D03*
X426696Y84104D03*
X414283Y84076D03*
X371500Y81700D03*
X395148Y72958D03*
X399318D03*
X439418Y33035D03*
X530160Y165898D03*
X521600Y165798D03*
X534348Y165858D03*
X516810Y205498D03*
X512680D03*
G54D26*
X50813Y89796D03*
X51465Y146761D03*
G54D35*
X99500Y52600D03*
X67800Y163800D03*
X94689Y135908D03*
X94685Y140036D03*
X102250Y164312D03*
Y168512D03*
X97672Y148907D03*
X97643Y153241D03*
X56300Y168300D03*
X117798Y89357D03*
X124600Y51900D03*
Y47700D03*
Y43500D03*
X112400Y74800D03*
X156900Y66400D03*
X117902Y98010D03*
X164754Y198330D03*
X243000Y180600D03*
Y176500D03*
X243200Y193200D03*
X207100Y195800D03*
X243200Y189000D03*
X234200Y198500D03*
X327000Y19700D03*
X332800Y52200D03*
X330700Y64700D03*
X334400Y69600D03*
X283400Y168400D03*
X302111Y198009D03*
X302000Y193700D03*
Y189700D03*
X293400Y187800D03*
X373687Y17368D03*
X383700Y13200D03*
X383800Y3300D03*
X373500Y7400D03*
X373700Y21500D03*
X426465Y30637D03*
X426400Y26500D03*
X386900Y69500D03*
X386800Y59600D03*
X376600Y65400D03*
X376813Y55568D03*
X386800Y46600D03*
X376800Y50700D03*
X376700Y38400D03*
X383700Y25800D03*
X450394Y52538D03*
X450406Y48469D03*
X448260Y66541D03*
X454600Y37100D03*
X541202Y176160D03*
Y172130D03*
G54D62*
X426219Y56060D03*
G54D71*
X539370Y190256D03*
Y206792D03*
X561024Y190256D03*
Y206792D03*
G54D44*
X75300Y163800D03*
X94676Y131798D03*
X95955Y144059D03*
X55900Y176800D03*
X56298Y172400D03*
X117820Y93564D03*
X121800Y74600D03*
X108365Y105330D03*
X109205Y109777D03*
X180100Y118500D03*
X172326Y198299D03*
X194013Y116998D03*
X241400Y117600D03*
X226698Y171220D03*
Y175550D03*
X226634Y195198D03*
X243198Y197300D03*
X234200Y194400D03*
X246400Y184900D03*
X327000Y23900D03*
X332800Y56300D03*
Y60400D03*
X306500Y116400D03*
X293400Y167600D03*
Y171800D03*
X373300Y-1200D03*
X373500Y3300D03*
X373683Y13318D03*
X383700Y17300D03*
X383800Y7400D03*
X360200Y-1800D03*
X373700Y25600D03*
X376600Y69500D03*
X418800Y30700D03*
X386800Y55500D03*
X418700Y26400D03*
X378400Y34200D03*
Y30100D03*
X386900Y65400D03*
X376817Y59618D03*
X386800Y50700D03*
X376800Y46600D03*
Y42500D03*
X383700Y21700D03*
X447528Y29487D03*
G54D53*
X168268Y143189D03*
Y223189D03*
X456258Y143189D03*
Y223189D03*
G54D72*
G01X-65001Y-234972D02*
Y-217472D01*
X-60635D01*
X-58888Y-218347D01*
X-57578Y-219514D01*
X-56486Y-221263D01*
X-55613Y-223306D01*
X-55395Y-226222D01*
X-55613Y-229139D01*
X-56486Y-231181D01*
X-57578Y-232931D01*
X-58888Y-234097D01*
X-60635Y-234972D01*
X-65001D01*
G01X-48157Y-217472D02*
X-42698Y-234972D01*
X-37239Y-217472D01*
G01X-25198D02*
Y-234972D01*
G01X-30220Y-217472D02*
X-20176D01*
G01X5435Y-234972D02*
Y-217472D01*
X10894D01*
X12640Y-218347D01*
X13732Y-219514D01*
X14169Y-221847D01*
X13732Y-224181D01*
X12422Y-225639D01*
X10894Y-226514D01*
X5435D01*
G01X10894D02*
X14169Y-234972D01*
G01X27302Y-223306D02*
Y-234972D01*
G01Y-218639D02*
X26865Y-218347D01*
Y-217764D01*
X27302Y-217472D01*
X27739Y-217764D01*
Y-218347D01*
X27302Y-218639D01*
G01X41527Y-232931D02*
X42619Y-234097D01*
X44147Y-234972D01*
X45457D01*
X46767Y-234389D01*
X47640Y-233514D01*
X48077Y-232348D01*
X47859Y-230597D01*
X46985Y-229722D01*
X43055Y-227972D01*
X42182Y-225930D01*
X42619Y-224472D01*
X43492Y-223597D01*
X44802Y-223306D01*
X46112Y-223597D01*
X47422Y-224472D01*
G01X59027Y-227097D02*
X66014D01*
X65359Y-225055D01*
X64267Y-223889D01*
X62739Y-223306D01*
X61210Y-223597D01*
X59900Y-224472D01*
X59027Y-226514D01*
X58590Y-228264D01*
Y-230014D01*
X59027Y-231764D01*
X60119Y-233514D01*
X61429Y-234680D01*
X62957Y-234972D01*
X64485Y-234389D01*
X66014Y-232639D01*
G01X76745Y-234972D02*
Y-223306D01*
G01Y-225639D02*
X77837Y-224472D01*
X78929Y-223597D01*
X80457Y-223306D01*
X81548Y-223597D01*
X82859Y-224472D01*
G01X119605Y-218931D02*
X118295Y-218055D01*
X116767Y-217472D01*
X115020D01*
X113055Y-218347D01*
X111527Y-219805D01*
X110435Y-221556D01*
X109562Y-224472D01*
X109343Y-227097D01*
X109780Y-229722D01*
X110435Y-231472D01*
X111745Y-233222D01*
X113274Y-234389D01*
X114802Y-234972D01*
X116330D01*
X117859Y-234389D01*
X119169Y-233514D01*
X120261Y-232348D01*
G01X136232Y-234972D02*
Y-223306D01*
G01Y-225347D02*
X135359Y-224181D01*
X134048Y-223597D01*
X132520Y-223306D01*
X130992Y-223889D01*
X129682Y-225055D01*
X128808Y-226805D01*
X128372Y-229139D01*
X128808Y-231472D01*
X129682Y-233222D01*
X130992Y-234389D01*
X132520Y-234972D01*
X134048Y-234680D01*
X135359Y-233806D01*
X136232Y-232639D01*
G01X146745Y-234972D02*
Y-223306D01*
G01Y-225639D02*
X147837Y-224472D01*
X148929Y-223597D01*
X150457Y-223306D01*
X151548Y-223597D01*
X152859Y-224472D01*
G01X171232Y-217472D02*
Y-234972D01*
G01Y-232348D02*
X170359Y-233806D01*
X169048Y-234680D01*
X167520Y-234972D01*
X165774Y-234389D01*
X164464Y-232931D01*
X163590Y-231181D01*
X163372Y-229139D01*
X163590Y-227097D01*
X164464Y-225347D01*
X165774Y-223889D01*
X167520Y-223306D01*
X169048Y-223597D01*
X170140Y-224181D01*
X171232Y-225347D01*
G01X178252Y-240805D02*
X191352D01*
G01X197717Y-232639D02*
X199464Y-234097D01*
X201429Y-234972D01*
X203175D01*
X204922Y-234097D01*
X206232Y-232639D01*
X206887Y-230597D01*
X206450Y-228556D01*
X205359Y-226805D01*
X203394Y-225639D01*
X200774Y-225055D01*
X199245Y-223889D01*
X198590Y-221847D01*
X199027Y-219805D01*
X200119Y-218347D01*
X201647Y-217472D01*
X203175D01*
X204704Y-218055D01*
X206014Y-219514D01*
G01X215217Y-232639D02*
X216964Y-234097D01*
X218929Y-234972D01*
X220675D01*
X222422Y-234097D01*
X223732Y-232639D01*
X224387Y-230597D01*
X223950Y-228556D01*
X222859Y-226805D01*
X220894Y-225639D01*
X218274Y-225055D01*
X216745Y-223889D01*
X216090Y-221847D01*
X216527Y-219805D01*
X217619Y-218347D01*
X219147Y-217472D01*
X220675D01*
X222204Y-218055D01*
X223514Y-219514D01*
G01X250654Y-220389D02*
X251964Y-218639D01*
X253492Y-217764D01*
X255239Y-217472D01*
X257422Y-218055D01*
X258950Y-219514D01*
X259387Y-221263D01*
X259169Y-223014D01*
X258295Y-224472D01*
X253929Y-227389D01*
X251964Y-229430D01*
X250654Y-232348D01*
X250217Y-234972D01*
X259387D01*
G01X286527Y-232931D02*
X287619Y-234097D01*
X289147Y-234972D01*
X290457D01*
X291767Y-234389D01*
X292640Y-233514D01*
X293077Y-232348D01*
X292859Y-230597D01*
X291985Y-229722D01*
X288055Y-227972D01*
X287182Y-225930D01*
X287619Y-224472D01*
X288492Y-223597D01*
X289802Y-223306D01*
X291112Y-223597D01*
X292422Y-224472D01*
G01X307302Y-234972D02*
Y-217472D01*
G01X324802Y-234972D02*
X323492Y-234680D01*
X322182Y-233514D01*
X321308Y-231472D01*
X320872Y-229139D01*
X321308Y-226805D01*
X322182Y-224764D01*
X323492Y-223597D01*
X324802Y-223306D01*
X326112Y-223597D01*
X327422Y-224764D01*
X328295Y-226805D01*
X328514Y-229139D01*
X328295Y-231472D01*
X327422Y-233514D01*
X326112Y-234680D01*
X324802Y-234972D01*
G01X342302Y-217472D02*
Y-234972D01*
G01X339245Y-223306D02*
X345359D01*
G01X356527Y-232931D02*
X357619Y-234097D01*
X359147Y-234972D01*
X360457D01*
X361767Y-234389D01*
X362640Y-233514D01*
X363077Y-232348D01*
X362859Y-230597D01*
X361985Y-229722D01*
X358055Y-227972D01*
X357182Y-225930D01*
X357619Y-224472D01*
X358492Y-223597D01*
X359802Y-223306D01*
X361112Y-223597D01*
X362422Y-224472D01*
G01X109125Y-189972D02*
Y-172472D01*
X114802Y-187055D01*
X120479Y-172472D01*
Y-189972D01*
G01X132302D02*
X130992Y-189680D01*
X129682Y-188514D01*
X128808Y-186472D01*
X128372Y-184139D01*
X128808Y-181805D01*
X129682Y-179764D01*
X130992Y-178597D01*
X132302Y-178306D01*
X133612Y-178597D01*
X134922Y-179764D01*
X135795Y-181805D01*
X136014Y-184139D01*
X135795Y-186472D01*
X134922Y-188514D01*
X133612Y-189680D01*
X132302Y-189972D01*
G01X153732Y-172472D02*
Y-189972D01*
G01Y-187348D02*
X152859Y-188806D01*
X151548Y-189680D01*
X150020Y-189972D01*
X148274Y-189389D01*
X146964Y-187931D01*
X146090Y-186181D01*
X145872Y-184139D01*
X146090Y-182097D01*
X146964Y-180347D01*
X148274Y-178889D01*
X150020Y-178306D01*
X151548Y-178597D01*
X152640Y-179181D01*
X153732Y-180347D01*
G01X164027Y-182097D02*
X171014D01*
X170359Y-180055D01*
X169267Y-178889D01*
X167739Y-178306D01*
X166210Y-178597D01*
X164900Y-179472D01*
X164027Y-181514D01*
X163590Y-183264D01*
Y-185014D01*
X164027Y-186764D01*
X165119Y-188514D01*
X166429Y-189680D01*
X167957Y-189972D01*
X169485Y-189389D01*
X171014Y-187639D01*
G01X184802Y-189972D02*
Y-172472D01*
G01X418602Y-234972D02*
Y-217472D01*
X415982Y-220972D01*
G01Y-234972D02*
X421222D01*
G01X431299Y-232348D02*
X432608Y-233806D01*
X434137Y-234680D01*
X436102Y-234972D01*
X438067Y-234389D01*
X439595Y-233222D01*
X440687Y-231181D01*
X440905Y-228847D01*
X440469Y-226514D01*
X439377Y-225055D01*
X437848Y-223889D01*
X436320Y-223597D01*
X434792Y-223889D01*
X432827Y-225055D01*
X433482Y-217472D01*
X439377D01*
G01X449890Y-232931D02*
X451419Y-234389D01*
X453165Y-234972D01*
X454912Y-234389D01*
X456440Y-232639D01*
X457532Y-230014D01*
X457969Y-227389D01*
Y-224181D01*
X457532Y-221556D01*
X456440Y-219222D01*
X455130Y-218055D01*
X453602Y-217472D01*
X451855Y-218055D01*
X450545Y-219222D01*
X449672Y-220972D01*
X449235Y-223306D01*
X449672Y-225347D01*
X450764Y-227389D01*
X452074Y-228556D01*
X453602Y-228847D01*
X455348Y-228264D01*
X456659Y-226805D01*
X457969Y-224181D01*
G01X466954Y-227681D02*
X468482Y-225639D01*
X469792Y-224472D01*
X471539Y-223889D01*
X473067Y-224472D01*
X474159Y-225639D01*
X475032Y-227389D01*
X475250Y-229430D01*
X475032Y-231181D01*
X474159Y-232931D01*
X472848Y-234389D01*
X471320Y-234972D01*
X469574Y-234389D01*
X468045Y-232639D01*
X467172Y-230014D01*
X466954Y-227097D01*
X467390Y-223306D01*
X468045Y-221263D01*
X469137Y-219222D01*
X470665Y-217764D01*
X472194Y-217472D01*
X473722Y-218055D01*
X474814Y-219514D01*
G01X488602Y-234972D02*
X490130Y-234680D01*
X491877Y-233806D01*
X492969Y-232348D01*
X493405Y-230305D01*
X492969Y-228264D01*
X491659Y-226514D01*
X489694Y-225639D01*
X487510D01*
X486200Y-225055D01*
X485108Y-223597D01*
X484672Y-221556D01*
X485327Y-219514D01*
X486855Y-218055D01*
X488602Y-217472D01*
X490348Y-218055D01*
X491877Y-219514D01*
X492532Y-221556D01*
X492095Y-223597D01*
X491004Y-225055D01*
X489694Y-225639D01*
X487510D01*
X485545Y-226514D01*
X484235Y-228264D01*
X483799Y-230305D01*
X484235Y-232348D01*
X485327Y-233806D01*
X487074Y-234680D01*
X488602Y-234972D01*
G01X405485Y-189972D02*
Y-172472D01*
X410725D01*
X412472Y-173347D01*
X413782Y-175389D01*
X414219Y-177722D01*
X413782Y-180055D01*
X412690Y-181805D01*
X410725Y-182681D01*
X405485D01*
G01X432155Y-173931D02*
X430845Y-173055D01*
X429317Y-172472D01*
X427570D01*
X425605Y-173347D01*
X424077Y-174805D01*
X422985Y-176556D01*
X422112Y-179472D01*
X421893Y-182097D01*
X422330Y-184722D01*
X422985Y-186472D01*
X424295Y-188222D01*
X425824Y-189389D01*
X427352Y-189972D01*
X428880D01*
X430409Y-189389D01*
X431719Y-188514D01*
X432811Y-187348D01*
G01X446598Y-180639D02*
X447472Y-179764D01*
X448127Y-178306D01*
X448564Y-176263D01*
X448127Y-174514D01*
X447254Y-173347D01*
X445725Y-172472D01*
X439830D01*
Y-189972D01*
X447035D01*
X448564Y-188806D01*
X449437Y-187055D01*
X449874Y-185014D01*
X449437Y-182972D01*
X448127Y-181222D01*
X446598Y-180639D01*
X439830D01*
G01X455802Y-195805D02*
X468902D01*
G01X474830Y-189972D02*
Y-172472D01*
X484874Y-189972D01*
Y-172472D01*
G01X497352Y-189972D02*
X495605Y-189680D01*
X494077Y-188514D01*
X492767Y-186764D01*
X491893Y-184722D01*
X491457Y-182389D01*
Y-180055D01*
X491893Y-177722D01*
X492767Y-175680D01*
X494077Y-173931D01*
X495605Y-172764D01*
X497352Y-172472D01*
X499098Y-172764D01*
X500627Y-173931D01*
X501937Y-175680D01*
X502811Y-177722D01*
X503247Y-180055D01*
Y-182389D01*
X502811Y-184722D01*
X501937Y-186764D01*
X500627Y-188514D01*
X499098Y-189680D01*
X497352Y-189972D01*
G01X571152Y-234972D02*
Y-217472D01*
X568532Y-220972D01*
G01Y-234972D02*
X573772D01*
G01X583193D02*
X588652Y-217472D01*
X594111Y-234972D01*
G01X592145Y-228847D02*
X585158D01*
G01X548193Y-172472D02*
X553652Y-189972D01*
X559111Y-172472D01*
G01X575519Y-189972D02*
X566785D01*
Y-172472D01*
X575519D01*
G01X572025Y-180930D02*
X566785D01*
G01X584285Y-189972D02*
Y-172472D01*
X589744D01*
X591490Y-173347D01*
X592582Y-174514D01*
X593019Y-176847D01*
X592582Y-179181D01*
X591272Y-180639D01*
X589744Y-181514D01*
X584285D01*
G01X589744D02*
X593019Y-189972D01*
G01X606152Y-190555D02*
X605715Y-190264D01*
Y-189680D01*
X606152Y-189389D01*
X606589Y-189680D01*
Y-190264D01*
X606152Y-190555D01*
G01X686102Y-217472D02*
Y-234972D01*
G01X681080Y-217472D02*
X691124D01*
G01X697925Y-234972D02*
Y-217472D01*
X703602Y-232055D01*
X709279Y-217472D01*
Y-234972D01*
G01X715643D02*
X721102Y-217472D01*
X726561Y-234972D01*
G01X724595Y-228847D02*
X717608D01*
G01X734017Y-232639D02*
X735764Y-234097D01*
X737729Y-234972D01*
X739475D01*
X741222Y-234097D01*
X742532Y-232639D01*
X743187Y-230597D01*
X742750Y-228556D01*
X741659Y-226805D01*
X739694Y-225639D01*
X737074Y-225055D01*
X735545Y-223889D01*
X734890Y-221847D01*
X735327Y-219805D01*
X736419Y-218347D01*
X737947Y-217472D01*
X739475D01*
X741004Y-218055D01*
X742314Y-219514D01*
G01X751299Y-234972D02*
Y-217472D01*
G01X759595D02*
X751299Y-228264D01*
G01X760905Y-234972D02*
X755010Y-223306D01*
G01X681735Y-172472D02*
Y-189972D01*
X690469D01*
G01X707532D02*
Y-178306D01*
G01Y-180347D02*
X706659Y-179181D01*
X705348Y-178597D01*
X703820Y-178306D01*
X702292Y-178889D01*
X700982Y-180055D01*
X700108Y-181805D01*
X699672Y-184139D01*
X700108Y-186472D01*
X700982Y-188222D01*
X702292Y-189389D01*
X703820Y-189972D01*
X705348Y-189680D01*
X706659Y-188806D01*
X707532Y-187639D01*
G01X716517Y-195222D02*
X717827Y-195805D01*
X719574Y-195222D01*
X720665Y-194056D01*
X721539Y-192597D01*
X722848Y-187931D01*
X725687Y-178306D01*
G01X718700D02*
X722848Y-187931D01*
G01X735327Y-182097D02*
X742314D01*
X741659Y-180055D01*
X740567Y-178889D01*
X739039Y-178306D01*
X737510Y-178597D01*
X736200Y-179472D01*
X735327Y-181514D01*
X734890Y-183264D01*
Y-185014D01*
X735327Y-186764D01*
X736419Y-188514D01*
X737729Y-189680D01*
X739257Y-189972D01*
X740785Y-189389D01*
X742314Y-187639D01*
G01X753045Y-189972D02*
Y-178306D01*
G01Y-180639D02*
X754137Y-179472D01*
X755229Y-178597D01*
X756757Y-178306D01*
X757848Y-178597D01*
X759159Y-179472D01*
G01X824705Y-218931D02*
X823395Y-218055D01*
X821867Y-217472D01*
X820120D01*
X818155Y-218347D01*
X816627Y-219805D01*
X815535Y-221556D01*
X814662Y-224472D01*
X814443Y-227097D01*
X814880Y-229722D01*
X815535Y-231472D01*
X816845Y-233222D01*
X818374Y-234389D01*
X819902Y-234972D01*
X821430D01*
X822959Y-234389D01*
X824269Y-233514D01*
X825361Y-232348D01*
G01X837402Y-234972D02*
X835655Y-234680D01*
X834127Y-233514D01*
X832817Y-231764D01*
X831943Y-229722D01*
X831507Y-227389D01*
Y-225055D01*
X831943Y-222722D01*
X832817Y-220680D01*
X834127Y-218931D01*
X835655Y-217764D01*
X837402Y-217472D01*
X839148Y-217764D01*
X840677Y-218931D01*
X841987Y-220680D01*
X842861Y-222722D01*
X843297Y-225055D01*
Y-227389D01*
X842861Y-229722D01*
X841987Y-231764D01*
X840677Y-233514D01*
X839148Y-234680D01*
X837402Y-234972D01*
G01X849880D02*
Y-217472D01*
X859924Y-234972D01*
Y-217472D01*
G01X867380Y-234972D02*
Y-217472D01*
X877424Y-234972D01*
Y-217472D01*
G01X887282D02*
X892522D01*
G01X889902D02*
Y-234972D01*
G01X887282D02*
X892522D01*
G01X911769D02*
X903035D01*
Y-217472D01*
X911769D01*
G01X908275Y-225930D02*
X903035D01*
G01X937817Y-234972D02*
X946987Y-217472D01*
G01X937817D02*
X946987Y-234972D01*
G01X955317D02*
Y-217472D01*
G01X964487D02*
Y-234972D01*
G01Y-226222D02*
X955317D01*
G01X823849Y-189972D02*
Y-172472D01*
X828215D01*
X829962Y-173347D01*
X831272Y-174514D01*
X832364Y-176263D01*
X833237Y-178306D01*
X833455Y-181222D01*
X833237Y-184139D01*
X832364Y-186181D01*
X831272Y-187931D01*
X829962Y-189097D01*
X828215Y-189972D01*
X823849D01*
G01X842877Y-182097D02*
X849864D01*
X849209Y-180055D01*
X848117Y-178889D01*
X846589Y-178306D01*
X845060Y-178597D01*
X843750Y-179472D01*
X842877Y-181514D01*
X842440Y-183264D01*
Y-185014D01*
X842877Y-186764D01*
X843969Y-188514D01*
X845279Y-189680D01*
X846807Y-189972D01*
X848335Y-189389D01*
X849864Y-187639D01*
G01X860377Y-187931D02*
X861469Y-189097D01*
X862997Y-189972D01*
X864307D01*
X865617Y-189389D01*
X866490Y-188514D01*
X866927Y-187348D01*
X866709Y-185597D01*
X865835Y-184722D01*
X861905Y-182972D01*
X861032Y-180930D01*
X861469Y-179472D01*
X862342Y-178597D01*
X863652Y-178306D01*
X864962Y-178597D01*
X866272Y-179472D01*
G01X881152Y-178306D02*
Y-189972D01*
G01Y-173639D02*
X880715Y-173347D01*
Y-172764D01*
X881152Y-172472D01*
X881589Y-172764D01*
Y-173347D01*
X881152Y-173639D01*
G01X895595Y-194347D02*
X897124Y-195514D01*
X898870Y-195805D01*
X900398Y-195514D01*
X901709Y-194056D01*
X902582Y-192014D01*
Y-178306D01*
G01Y-180639D02*
X901709Y-179472D01*
X900398Y-178597D01*
X898870Y-178306D01*
X897124Y-178889D01*
X896032Y-180055D01*
X895158Y-182097D01*
X894722Y-184139D01*
X894940Y-185889D01*
X895814Y-187931D01*
X897124Y-189389D01*
X898870Y-189972D01*
X900180Y-189680D01*
X901709Y-188514D01*
X902582Y-187348D01*
G01X912440Y-189972D02*
Y-178306D01*
G01Y-181222D02*
X913314Y-179764D01*
X914624Y-178597D01*
X916370Y-178306D01*
X917898Y-178597D01*
X919209Y-179764D01*
X919864Y-181805D01*
Y-189972D01*
G01X930377Y-182097D02*
X937364D01*
X936709Y-180055D01*
X935617Y-178889D01*
X934089Y-178306D01*
X932560Y-178597D01*
X931250Y-179472D01*
X930377Y-181514D01*
X929940Y-183264D01*
Y-185014D01*
X930377Y-186764D01*
X931469Y-188514D01*
X932779Y-189680D01*
X934307Y-189972D01*
X935835Y-189389D01*
X937364Y-187639D01*
G01X948095Y-189972D02*
Y-178306D01*
G01Y-180639D02*
X949187Y-179472D01*
X950279Y-178597D01*
X951807Y-178306D01*
X952898Y-178597D01*
X954209Y-179472D01*
G01X994852Y-217472D02*
X993105Y-218055D01*
X991795Y-219514D01*
X990922Y-221263D01*
X990267Y-223597D01*
X990049Y-226222D01*
X990267Y-228847D01*
X990922Y-231181D01*
X991795Y-232931D01*
X993105Y-234389D01*
X994852Y-234972D01*
X996598Y-234389D01*
X997909Y-232931D01*
X998782Y-231181D01*
X999437Y-228847D01*
X999655Y-226222D01*
X999437Y-223597D01*
X998782Y-221263D01*
X997909Y-219514D01*
X996598Y-218055D01*
X994852Y-217472D01*
G01X1012352Y-234972D02*
X1013880Y-234680D01*
X1015627Y-233806D01*
X1016719Y-232348D01*
X1017155Y-230305D01*
X1016719Y-228264D01*
X1015409Y-226514D01*
X1013444Y-225639D01*
X1011260D01*
X1009950Y-225055D01*
X1008858Y-223597D01*
X1008422Y-221556D01*
X1009077Y-219514D01*
X1010605Y-218055D01*
X1012352Y-217472D01*
X1014098Y-218055D01*
X1015627Y-219514D01*
X1016282Y-221556D01*
X1015845Y-223597D01*
X1014754Y-225055D01*
X1013444Y-225639D01*
X1011260D01*
X1009295Y-226514D01*
X1007985Y-228264D01*
X1007549Y-230305D01*
X1007985Y-232348D01*
X1009077Y-233806D01*
X1010824Y-234680D01*
X1012352Y-234972D01*
G01X1025922Y-235555D02*
X1033782Y-217472D01*
G01X1043204Y-220389D02*
X1044514Y-218639D01*
X1046042Y-217764D01*
X1047789Y-217472D01*
X1049972Y-218055D01*
X1051500Y-219514D01*
X1051937Y-221263D01*
X1051719Y-223014D01*
X1050845Y-224472D01*
X1046479Y-227389D01*
X1044514Y-229430D01*
X1043204Y-232348D01*
X1042767Y-234972D01*
X1051937D01*
G01X1060049Y-232348D02*
X1061358Y-233806D01*
X1062887Y-234680D01*
X1064852Y-234972D01*
X1066817Y-234389D01*
X1068345Y-233222D01*
X1069437Y-231181D01*
X1069655Y-228847D01*
X1069219Y-226514D01*
X1068127Y-225055D01*
X1066598Y-223889D01*
X1065070Y-223597D01*
X1063542Y-223889D01*
X1061577Y-225055D01*
X1062232Y-217472D01*
X1068127D01*
G01X1078422Y-235555D02*
X1086282Y-217472D01*
G01X1095704Y-220389D02*
X1097014Y-218639D01*
X1098542Y-217764D01*
X1100289Y-217472D01*
X1102472Y-218055D01*
X1104000Y-219514D01*
X1104437Y-221263D01*
X1104219Y-223014D01*
X1103345Y-224472D01*
X1098979Y-227389D01*
X1097014Y-229430D01*
X1095704Y-232348D01*
X1095267Y-234972D01*
X1104437D01*
G01X1117352Y-217472D02*
X1115605Y-218055D01*
X1114295Y-219514D01*
X1113422Y-221263D01*
X1112767Y-223597D01*
X1112549Y-226222D01*
X1112767Y-228847D01*
X1113422Y-231181D01*
X1114295Y-232931D01*
X1115605Y-234389D01*
X1117352Y-234972D01*
X1119098Y-234389D01*
X1120409Y-232931D01*
X1121282Y-231181D01*
X1121937Y-228847D01*
X1122155Y-226222D01*
X1121937Y-223597D01*
X1121282Y-221263D01*
X1120409Y-219514D01*
X1119098Y-218055D01*
X1117352Y-217472D01*
G01X1134852Y-234972D02*
Y-217472D01*
X1132232Y-220972D01*
G01Y-234972D02*
X1137472D01*
G01X1148204Y-227681D02*
X1149732Y-225639D01*
X1151042Y-224472D01*
X1152789Y-223889D01*
X1154317Y-224472D01*
X1155409Y-225639D01*
X1156282Y-227389D01*
X1156500Y-229430D01*
X1156282Y-231181D01*
X1155409Y-232931D01*
X1154098Y-234389D01*
X1152570Y-234972D01*
X1150824Y-234389D01*
X1149295Y-232639D01*
X1148422Y-230014D01*
X1148204Y-227097D01*
X1148640Y-223306D01*
X1149295Y-221263D01*
X1150387Y-219222D01*
X1151915Y-217764D01*
X1153444Y-217472D01*
X1154972Y-218055D01*
X1156064Y-219514D01*
G01X1042549Y-189972D02*
Y-172472D01*
X1046915D01*
X1048662Y-173347D01*
X1049972Y-174514D01*
X1051064Y-176263D01*
X1051937Y-178306D01*
X1052155Y-181222D01*
X1051937Y-184139D01*
X1051064Y-186181D01*
X1049972Y-187931D01*
X1048662Y-189097D01*
X1046915Y-189972D01*
X1042549D01*
G01X1068782D02*
Y-178306D01*
G01Y-180347D02*
X1067909Y-179181D01*
X1066598Y-178597D01*
X1065070Y-178306D01*
X1063542Y-178889D01*
X1062232Y-180055D01*
X1061358Y-181805D01*
X1060922Y-184139D01*
X1061358Y-186472D01*
X1062232Y-188222D01*
X1063542Y-189389D01*
X1065070Y-189972D01*
X1066598Y-189680D01*
X1067909Y-188806D01*
X1068782Y-187639D01*
G01X1082352Y-172472D02*
Y-189972D01*
G01X1079295Y-178306D02*
X1085409D01*
G01X1096577Y-182097D02*
X1103564D01*
X1102909Y-180055D01*
X1101817Y-178889D01*
X1100289Y-178306D01*
X1098760Y-178597D01*
X1097450Y-179472D01*
X1096577Y-181514D01*
X1096140Y-183264D01*
Y-185014D01*
X1096577Y-186764D01*
X1097669Y-188514D01*
X1098979Y-189680D01*
X1100507Y-189972D01*
X1102035Y-189389D01*
X1103564Y-187639D01*
G54D27*
X53357Y92340D03*
X54009Y149305D03*
G54D18*
X109200Y-26200D03*
Y-15200D03*
G54D36*
X101722Y86658D03*
X103691D03*
X105659D03*
Y98870D03*
X103691D03*
X101722D03*
X76226Y134181D03*
X78195D03*
X80163D03*
X82132D03*
Y146393D03*
X80163D03*
X78195D03*
X76226D03*
X107628Y86658D03*
Y98870D03*
G54D45*
X78700Y163800D03*
X98076Y131798D03*
X99355Y144059D03*
X59300Y176800D03*
X59698Y172400D03*
X121220Y93564D03*
X125200Y74600D03*
X111765Y105330D03*
X112605Y109777D03*
X183500Y118500D03*
X175726Y198299D03*
X197413Y116998D03*
X244800Y117600D03*
X230098Y171220D03*
Y175550D03*
X230034Y195198D03*
X246598Y197300D03*
X237600Y194400D03*
X249800Y184900D03*
X330400Y23900D03*
X336200Y56300D03*
Y60400D03*
X309900Y116400D03*
X296800Y167600D03*
Y171800D03*
X376700Y-1200D03*
X376900Y3300D03*
X377083Y13318D03*
X387100Y17300D03*
X387200Y7400D03*
X363600Y-1800D03*
X377100Y25600D03*
X380000Y69500D03*
X422200Y30700D03*
X390200Y55500D03*
X422100Y26400D03*
X381800Y34200D03*
Y30100D03*
X390300Y65400D03*
X380217Y59618D03*
X390200Y50700D03*
X380200Y46600D03*
Y42500D03*
X387100Y21700D03*
X450928Y29487D03*
G54D54*
X122403Y148109D03*
X126338Y155984D03*
X130278Y148109D03*
X134213Y155984D03*
X138148Y148109D03*
X142088Y155984D03*
X146023Y148109D03*
X149963Y155984D03*
X153898Y148109D03*
X157833Y155984D03*
X161773Y148109D03*
X173583Y155984D03*
X177518Y148109D03*
X181458Y155984D03*
X185393Y148109D03*
X189333Y155984D03*
X122403Y138269D03*
X126338Y130394D03*
X130278Y138269D03*
X134213Y130394D03*
X138148Y138269D03*
X142088Y130394D03*
X146023Y138269D03*
X149963Y130394D03*
X153898Y138269D03*
X157833Y130394D03*
X161773Y138269D03*
X173583Y130394D03*
X177518Y138269D03*
X181458Y130394D03*
X185393Y138269D03*
X189333Y130394D03*
X122403Y228109D03*
X126338Y235984D03*
X130278Y228109D03*
X134213Y235984D03*
X138148Y228109D03*
X142088Y235984D03*
X146023Y228109D03*
X149963Y235984D03*
X153898Y228109D03*
X157833Y235984D03*
X161773Y228109D03*
X173583Y235984D03*
X177518Y228109D03*
X181458Y235984D03*
X185393Y228109D03*
X189333Y235984D03*
X122403Y218269D03*
X126338Y210394D03*
X130278Y218269D03*
X134213Y210394D03*
X138148Y218269D03*
X142088Y210394D03*
X146023Y218269D03*
X149963Y210394D03*
X153898Y218269D03*
X157833Y210394D03*
X161773Y218269D03*
X173583Y210394D03*
X177518Y218269D03*
X181458Y210394D03*
X185393Y218269D03*
X189333Y210394D03*
X193268Y148109D03*
X197203Y155984D03*
X201143Y148109D03*
X205078Y155984D03*
X209018Y148109D03*
X212953Y155984D03*
X216888Y148109D03*
X220828Y155984D03*
X224763Y148109D03*
X228703Y155984D03*
X232638Y148109D03*
X236573Y155984D03*
X240513Y148109D03*
X244448Y155984D03*
X248388Y148109D03*
X252323Y155984D03*
X256258Y148109D03*
X260198Y155984D03*
X264133Y148109D03*
X268073Y155984D03*
X193268Y138269D03*
X197203Y130394D03*
X201143Y138269D03*
X205078Y130394D03*
X209018Y138269D03*
X212953Y130394D03*
X216888Y138269D03*
X220828Y130394D03*
X224763Y138269D03*
X228703Y130394D03*
X232638Y138269D03*
X236573Y130394D03*
X240513Y138269D03*
X244448Y130394D03*
X248388Y138269D03*
X252323Y130394D03*
X256258Y138269D03*
X260198Y130394D03*
X264133Y138269D03*
X268073Y130394D03*
X193268Y228109D03*
X197203Y235984D03*
X201143Y228109D03*
X205078Y235984D03*
X209018Y228109D03*
X212953Y235984D03*
X216888Y228109D03*
X220828Y235984D03*
X224763Y228109D03*
X228703Y235984D03*
X232638Y228109D03*
X236573Y235984D03*
X240513Y228109D03*
X244448Y235984D03*
X248388Y228109D03*
X252323Y235984D03*
X256258Y228109D03*
X260198Y235984D03*
X264133Y228109D03*
X268073Y235984D03*
X193268Y218269D03*
X197203Y210394D03*
X201143Y218269D03*
X205078Y210394D03*
X209018Y218269D03*
X212953Y210394D03*
X216888Y218269D03*
X220828Y210394D03*
X224763Y218269D03*
X228703Y210394D03*
X232638Y218269D03*
X236573Y210394D03*
X240513Y218269D03*
X244448Y210394D03*
X248388Y218269D03*
X252323Y210394D03*
X256258Y218269D03*
X260198Y210394D03*
X264133Y218269D03*
X268073Y210394D03*
X272008Y148109D03*
X275943Y155984D03*
X279883Y148109D03*
X283818Y155984D03*
X287758Y148109D03*
X291693Y155984D03*
X295628Y148109D03*
X299568Y155984D03*
X303503Y148109D03*
X307443Y155984D03*
X311378Y148109D03*
X315313Y155984D03*
X319253Y148109D03*
X323188Y155984D03*
X327128Y148109D03*
X331063Y155984D03*
X334998Y148109D03*
X338938Y155984D03*
X342873Y148109D03*
X346813Y155984D03*
X272008Y138269D03*
X275943Y130394D03*
X279883Y138269D03*
X283818Y130394D03*
X287758Y138269D03*
X291693Y130394D03*
X295628Y138269D03*
X299568Y130394D03*
X303503Y138269D03*
X307443Y130394D03*
X311378Y138269D03*
X315313Y130394D03*
X319253Y138269D03*
X323188Y130394D03*
X327128Y138269D03*
X331063Y130394D03*
X334998Y138269D03*
X338938Y130394D03*
X342873Y138269D03*
X346813Y130394D03*
X272008Y228109D03*
X275943Y235984D03*
X279883Y228109D03*
X283818Y235984D03*
X287758Y228109D03*
X291693Y235984D03*
X295628Y228109D03*
X299568Y235984D03*
X303503Y228109D03*
X307443Y235984D03*
X311378Y228109D03*
X315313Y235984D03*
X319253Y228109D03*
X323188Y235984D03*
X327128Y228109D03*
X331063Y235984D03*
X334998Y228109D03*
X338938Y235984D03*
X342873Y228109D03*
X346813Y235984D03*
X272008Y218269D03*
X275943Y210394D03*
X279883Y218269D03*
X283818Y210394D03*
X287758Y218269D03*
X291693Y210394D03*
X295628Y218269D03*
X299568Y210394D03*
X303503Y218269D03*
X307443Y210394D03*
X311378Y218269D03*
X315313Y210394D03*
X319253Y218269D03*
X323188Y210394D03*
X327128Y218269D03*
X331063Y210394D03*
X334998Y218269D03*
X338938Y210394D03*
X342873Y218269D03*
X346813Y210394D03*
X350748Y148109D03*
X354683Y155984D03*
X358623Y148109D03*
X362558Y155984D03*
X366498Y148109D03*
X370433Y155984D03*
X374368Y148109D03*
X378308Y155984D03*
X382243Y148109D03*
X386183Y155984D03*
X390118Y148109D03*
X394053Y155984D03*
X397993Y148109D03*
X401928Y155984D03*
X405868Y148109D03*
X409803Y155984D03*
X413738Y148109D03*
X417678Y155984D03*
X421613Y148109D03*
X425553Y155984D03*
X429488Y148109D03*
X350748Y138269D03*
X354683Y130394D03*
X358623Y138269D03*
X362558Y130394D03*
X366498Y138269D03*
X370433Y130394D03*
X374368Y138269D03*
X378308Y130394D03*
X382243Y138269D03*
X386183Y130394D03*
X390118Y138269D03*
X394053Y130394D03*
X397993Y138269D03*
X401928Y130394D03*
X405868Y138269D03*
X409803Y130394D03*
X413738Y138269D03*
X417678Y130394D03*
X421613Y138269D03*
X425553Y130394D03*
X429488Y138269D03*
X350748Y228109D03*
X354683Y235984D03*
X358623Y228109D03*
X362558Y235984D03*
X366498Y228109D03*
X370433Y235984D03*
X374368Y228109D03*
X378308Y235984D03*
X382243Y228109D03*
X386183Y235984D03*
X390118Y228109D03*
X394053Y235984D03*
X397993Y228109D03*
X401928Y235984D03*
X405868Y228109D03*
X409803Y235984D03*
X413738Y228109D03*
X417678Y235984D03*
X421613Y228109D03*
X425553Y235984D03*
X429488Y228109D03*
X350748Y218269D03*
X354683Y210394D03*
X358623Y218269D03*
X362558Y210394D03*
X366498Y218269D03*
X370433Y210394D03*
X374368Y218269D03*
X378308Y210394D03*
X382243Y218269D03*
X386183Y210394D03*
X390118Y218269D03*
X394053Y210394D03*
X397993Y218269D03*
X401928Y210394D03*
X405868Y218269D03*
X409803Y210394D03*
X413738Y218269D03*
X417678Y210394D03*
X421613Y218269D03*
X425553Y210394D03*
X429488Y218269D03*
X433423Y155984D03*
X437363Y148109D03*
X441298Y155984D03*
X445238Y148109D03*
X449173Y155984D03*
X433423Y130394D03*
X437363Y138269D03*
X441298Y130394D03*
X445238Y138269D03*
X449173Y130394D03*
X433423Y235984D03*
X437363Y228109D03*
X441298Y235984D03*
X445238Y228109D03*
X449173Y235984D03*
X433423Y210394D03*
X437363Y218269D03*
X441298Y210394D03*
X445238Y218269D03*
X449173Y210394D03*
G54D63*
X410970Y37500D03*
X407357Y45482D03*
X404023Y61327D03*
X406449Y40438D03*
X448600Y109400D03*
X471500Y209500D03*
G54D28*
X102500Y65800D03*
X59600Y206900D03*
X133100Y56200D03*
X520600Y196600D03*
G54D19*
X85400Y48400D03*
X89978Y126933D03*
X95068Y126988D03*
X99160Y229024D03*
X89548Y229126D03*
X94401Y229011D03*
X84631Y229140D03*
X157100Y84400D03*
X434600Y21600D03*
G54D55*
X165800Y103800D03*
G54D37*
X98569Y95717D03*
Y93748D03*
Y91780D03*
Y89811D03*
X73073Y143240D03*
Y141271D03*
Y139303D03*
Y137334D03*
X85285D03*
Y139303D03*
Y141271D03*
Y143240D03*
X110781Y89811D03*
Y91780D03*
Y93748D03*
Y95717D03*
G54D46*
X66197Y173644D03*
X68757D03*
X71317D03*
X73877D03*
X76437D03*
X78997D03*
X81557D03*
X84117D03*
X86677D03*
X89237D03*
Y195844D03*
X86677D03*
X84117D03*
X81557D03*
X78997D03*
X76437D03*
X73877D03*
X71317D03*
X68757D03*
X66197D03*
X205780Y172408D03*
X203220D03*
X200660D03*
X198100D03*
Y188588D03*
X200660D03*
X203220D03*
X205780D03*
X402330Y12412D03*
X399770D03*
X397210D03*
X394650D03*
Y28592D03*
X397210D03*
X399770D03*
X402330D03*
G54D64*
X428027Y88710D03*
X445795Y78376D03*
G54D29*
X102500Y69400D03*
X59600Y210500D03*
X133100Y59800D03*
X520600Y200200D03*
G54D38*
X104675Y92764D03*
X79179Y140287D03*
X521920Y181702D03*
G54D47*
X40794Y230682D03*
X37095Y524125D03*
X540347Y32747D03*
X572386Y532294D03*
X601314Y-26920D03*
X599868Y229462D03*
G54D65*
X444705Y-64309D03*
X447854D03*
X451004D03*
X454154D03*
X457303D03*
X460453D03*
X463602D03*
X466752D03*
X469902D03*
X473051D03*
X476201D03*
X479350D03*
X482500D03*
X485650D03*
X488799D03*
X491949D03*
X495098D03*
X498248D03*
X501398D03*
X504547D03*
X507697D03*
X510846D03*
X513996D03*
X517146D03*
X520295D03*
X523445D03*
X526594D03*
X529744D03*
X532894D03*
X536043D03*
G54D56*
X171400Y103800D03*
G54D48*
X150588Y-42D03*
X153148D03*
X155708D03*
Y7358D03*
X153148D03*
X150588D03*
G54D57*
X259944Y178583D03*
Y176023D03*
Y173463D03*
Y196503D03*
Y193943D03*
Y191383D03*
Y188823D03*
Y186263D03*
Y183703D03*
Y181143D03*
X341438Y2889D03*
Y5449D03*
Y8009D03*
Y10569D03*
Y13129D03*
Y15689D03*
Y18249D03*
Y20809D03*
Y23369D03*
Y25929D03*
Y28489D03*
Y31049D03*
X344638Y39889D03*
Y42449D03*
Y45009D03*
Y47569D03*
Y50129D03*
Y52689D03*
Y55249D03*
Y57809D03*
Y60369D03*
Y62929D03*
Y65489D03*
Y68049D03*
X282144Y173463D03*
Y176023D03*
Y178583D03*
Y181143D03*
Y183703D03*
Y186263D03*
Y188823D03*
Y191383D03*
Y193943D03*
Y196503D03*
X363638Y18249D03*
Y15689D03*
Y13129D03*
Y10569D03*
Y8009D03*
Y5449D03*
Y2889D03*
Y31049D03*
Y28489D03*
Y25929D03*
Y23369D03*
Y20809D03*
X366838Y68049D03*
Y65489D03*
Y62929D03*
Y60369D03*
Y57809D03*
Y55249D03*
Y52689D03*
Y50129D03*
Y47569D03*
Y45009D03*
Y42449D03*
Y39889D03*
G54D66*
X433627Y88710D03*
X451395Y78376D03*
G54D39*
X71000Y100900D03*
Y120100D03*
G54D67*
X468381Y66114D03*
X459157D03*
Y72070D03*
X468381D03*
G54D58*
X418345Y44560D03*
Y67560D03*
X434093Y44560D03*
Y67560D03*
G54D49*
X157100Y62300D03*
X143000Y86000D03*
Y82400D03*
Y78700D03*
X289000Y196800D03*
X365600Y35400D03*
X408700Y33400D03*
X447520Y33313D03*
X465391Y60100D03*
X447388Y74043D03*
X450400Y44300D03*
X431634Y84295D03*
X448831Y60176D03*
X513082Y198350D03*
G54D59*
X414719Y63934D03*
Y48186D03*
X437719D03*
Y63934D03*
G54D68*
X515814Y178749D03*
X528026D03*
X515814Y184655D03*
Y182686D03*
Y180718D03*
X528026D03*
Y182686D03*
Y184655D03*
G54D69*
X518967Y175596D03*
X520936D03*
X522904D03*
X524873D03*
Y187808D03*
X522904D03*
X520936D03*
X518967D03*
M02*
